(kicad_pcb
	(version 20260206)
	(generator "pcbnew")
	(generator_version "10.0")
	(general
		(thickness 1.6)
		(legacy_teardrops no)
	)
	(paper "A4")
	(title_block
		(title "04192023_DAF0TMB3IC0_F0TG_MB_C_brd_V02_OCP.brd")
		(comment 1 "Grand Teton / footprints 4577-4582 of 8354")
	)
	(layers
		(0 "F.Cu" signal "TOP")
		(4 "In1.Cu" signal "GND")
		(6 "In2.Cu" signal "IN1")
		(8 "In3.Cu" signal "GND1")
		(10 "In4.Cu" signal "IN2")
		(12 "In5.Cu" signal "GND2")
		(14 "In6.Cu" signal "IN3")
		(16 "In7.Cu" signal "GND3")
		(18 "In8.Cu" signal "VCC")
		(20 "In9.Cu" signal "VCC1")
		(22 "In10.Cu" signal "GND4")
		(24 "In11.Cu" signal "IN4")
		(26 "In12.Cu" signal "GND5")
		(28 "In13.Cu" signal "IN5")
		(30 "In14.Cu" signal "GND6")
		(32 "In15.Cu" signal "IN6")
		(34 "In16.Cu" signal "GND7")
		(2 "B.Cu" signal "BOTTOM")
		(9 "F.Adhes" user "F.Adhesive")
		(11 "B.Adhes" user "B.Adhesive")
		(13 "F.Paste" user "Package Geometry/Pastemask Top")
		(15 "B.Paste" user "Package Geometry/Pastemask Bottom")
		(5 "F.SilkS" user "Ref Des/Silkscreen Top")
		(7 "B.SilkS" user "Ref Des/Silkscreen Bottom")
		(1 "F.Mask" user "Board Geometry/Soldermask Top")
		(3 "B.Mask" user "Board Geometry/Soldermask Bottom")
		(17 "Dwgs.User" user "User.Drawings")
		(19 "Cmts.User" user "User.Comments")
		(21 "Eco1.User" user "User.Eco1")
		(23 "Eco2.User" user "User.Eco2")
		(25 "Edge.Cuts" user "Board Geometry/Outline")
		(27 "Margin" user)
		(31 "F.CrtYd" user "Package Geometry/Place Bound Top")
		(29 "B.CrtYd" user "Package Geometry/Place Bound Bottom")
		(35 "F.Fab" user "Ref Des/Assembly Top")
		(33 "B.Fab" user "Ref Des/Assembly Bottom")
	)
	(footprint ""
		(layer "F.Cu")
		(at 68.147438 -32.776922 90)
		(property "Reference" "PR3847"
			(at 0 0 90)
			(layer "F.SilkS")
			(hide yes)
			(effects
				(font
					(size 1.27 1.27)
				)
			)
		)
		(property "Value" ""
			(at 0 0 90)
			(layer "F.Fab")
			(effects
				(font
					(size 1.27 1.27)
				)
			)
		)
		(duplicate_pad_numbers_are_jumpers no)
		(fp_line
			(start 0.7874 -0.4064)
			(end 0.7874 0.4064)
			(stroke
				(width 0.1524)
				(type default)
			)
			(layer "F.SilkS")
		)
		(fp_line
			(start -0.7874 -0.4064)
			(end 0.7874 -0.4064)
			(stroke
				(width 0.1524)
				(type default)
			)
			(layer "F.SilkS")
		)
		(fp_line
			(start 0.7874 0.4064)
			(end -0.7874 0.4064)
			(stroke
				(width 0.1524)
				(type default)
			)
			(layer "F.SilkS")
		)
		(fp_line
			(start -0.7874 0.4064)
			(end -0.7874 -0.4064)
			(stroke
				(width 0.1524)
				(type default)
			)
			(layer "F.SilkS")
		)
		(fp_line
			(start -0.12065 -0.305054)
			(end -0.12065 -0.2794)
			(stroke
				(width 0.1)
				(type default)
			)
			(layer "F.Fab")
		)
		(fp_line
			(start -0.67945 -0.305054)
			(end -0.12065 -0.305054)
			(stroke
				(width 0.1)
				(type default)
			)
			(layer "F.Fab")
		)
		(fp_line
			(start 0.67945 -0.3048)
			(end 0.67945 0.3048)
			(stroke
				(width 0.1)
				(type default)
			)
			(layer "F.Fab")
		)
		(fp_line
			(start 0.12065 -0.3048)
			(end 0.67945 -0.3048)
			(stroke
				(width 0.1)
				(type default)
			)
			(layer "F.Fab")
		)
		(fp_line
			(start 0.12065 -0.2794)
			(end 0.12065 -0.3048)
			(stroke
				(width 0.1)
				(type default)
			)
			(layer "F.Fab")
		)
		(fp_line
			(start -0.12065 -0.2794)
			(end 0.12065 -0.2794)
			(stroke
				(width 0.1)
				(type default)
			)
			(layer "F.Fab")
		)
		(fp_line
			(start 0.120396 0.2794)
			(end -0.12065 0.2794)
			(stroke
				(width 0.1)
				(type default)
			)
			(layer "F.Fab")
		)
		(fp_line
			(start -0.12065 0.2794)
			(end -0.12065 0.3048)
			(stroke
				(width 0.1)
				(type default)
			)
			(layer "F.Fab")
		)
		(fp_line
			(start 0.67945 0.3048)
			(end 0.120396 0.3048)
			(stroke
				(width 0.1)
				(type default)
			)
			(layer "F.Fab")
		)
		(fp_line
			(start 0.120396 0.3048)
			(end 0.120396 0.2794)
			(stroke
				(width 0.1)
				(type default)
			)
			(layer "F.Fab")
		)
		(fp_line
			(start -0.12065 0.3048)
			(end -0.67945 0.3048)
			(stroke
				(width 0.1)
				(type default)
			)
			(layer "F.Fab")
		)
		(fp_line
			(start -0.67945 0.3048)
			(end -0.67945 -0.305054)
			(stroke
				(width 0.1)
				(type default)
			)
			(layer "F.Fab")
		)
		(pad "1" smd circle
			(at -0.40005 0 90)
			(size 0 0)
			(layers "F.Cu" "F.Mask" "F.Paste")
			(net "P12V_OCP_ISET_2")
		)
		(pad "2" smd circle
			(at 0.40005 0 90)
			(size 0 0)
			(layers "F.Cu" "F.Mask" "F.Paste")
			(net "GND")
		)
	)
	(footprint ""
		(layer "F.Cu")
		(at 340.969346 -20.093686 -90)
		(property "Reference" "Q2"
			(at -0.023114 1.751076 90)
			(unlocked yes)
			(layer "F.SilkS")
			(effects
				(font
					(size 0.7874 0.5842)
					(thickness 0.1524)
				)
				(justify left)
			)
		)
		(property "Value" ""
			(at 0 0 270)
			(layer "F.Fab")
			(effects
				(font
					(size 1.27 1.27)
				)
			)
		)
		(duplicate_pad_numbers_are_jumpers no)
		(fp_line
			(start -1.332738 1.100074)
			(end -1.332738 -1.100074)
			(stroke
				(width 0.1524)
				(type default)
			)
			(layer "F.SilkS")
		)
		(fp_line
			(start 1.332738 1.100074)
			(end -1.332738 1.100074)
			(stroke
				(width 0.1524)
				(type default)
			)
			(layer "F.SilkS")
		)
		(fp_line
			(start 0 -0.541274)
			(end 0.4826 -1.100074)
			(stroke
				(width 0.1524)
				(type default)
			)
			(layer "F.SilkS")
		)
		(fp_line
			(start -1.332738 -1.100074)
			(end -0.4826 -1.100074)
			(stroke
				(width 0.1524)
				(type default)
			)
			(layer "F.SilkS")
		)
		(fp_line
			(start -0.4826 -1.100074)
			(end 0 -0.541274)
			(stroke
				(width 0.1524)
				(type default)
			)
			(layer "F.SilkS")
		)
		(fp_line
			(start 0.4826 -1.100074)
			(end 1.332738 -1.100074)
			(stroke
				(width 0.1524)
				(type default)
			)
			(layer "F.SilkS")
		)
		(fp_line
			(start 1.332738 -1.100074)
			(end 1.332738 1.100074)
			(stroke
				(width 0.1524)
				(type default)
			)
			(layer "F.SilkS")
		)
		(fp_poly
			(pts
				(xy -2.067306 -0.649986) (xy -2.769362 -0.298958) (xy -2.769362 -1.001014)
			)
			(stroke
				(width 0)
				(type default)
			)
			(fill yes)
			(layer "F.SilkS")
		)
		(fp_line
			(start -0.674878 1.100074)
			(end -0.674878 -1.100074)
			(stroke
				(width 0.1)
				(type default)
			)
			(layer "F.Fab")
		)
		(fp_line
			(start 0.674878 1.100074)
			(end -0.674878 1.100074)
			(stroke
				(width 0.1)
				(type default)
			)
			(layer "F.Fab")
		)
		(fp_line
			(start -0.674878 -1.100074)
			(end 0.674878 -1.100074)
			(stroke
				(width 0.1)
				(type default)
			)
			(layer "F.Fab")
		)
		(fp_line
			(start 0.674878 -1.100074)
			(end 0.674878 1.100074)
			(stroke
				(width 0.1)
				(type default)
			)
			(layer "F.Fab")
		)
		(fp_poly
			(pts
				(xy -2.2352 -0.298958) (xy -2.2352 -1.001014) (xy -1.533144 -0.649986)
			)
			(stroke
				(width 0)
				(type default)
			)
			(fill yes)
			(layer "F.Fab")
		)
		(pad "1" smd rect
			(at -0.94996 -0.649986)
			(size 0.4318 0.508)
			(layers "F.Cu" "F.Mask" "F.Paste")
			(net "GND")
		)
		(pad "2" smd rect
			(at -0.94996 0)
			(size 0.4318 0.508)
			(layers "F.Cu" "F.Mask" "F.Paste")
			(net "BOOT_RDY_BUF_LED")
		)
		(pad "3" smd rect
			(at -0.94996 0.649986)
			(size 0.4318 0.508)
			(layers "F.Cu" "F.Mask" "F.Paste")
			(net "BOOT_RDY_LED_N")
		)
		(pad "4" smd rect
			(at 0.94996 0.649986)
			(size 0.4318 0.508)
			(layers "F.Cu" "F.Mask" "F.Paste")
			(net "GND")
		)
		(pad "5" smd rect
			(at 0.94996 0)
			(size 0.4318 0.508)
			(layers "F.Cu" "F.Mask" "F.Paste")
			(net "BOOT_RDY_LED")
		)
		(pad "6" smd rect
			(at 0.94996 -0.649986)
			(size 0.4318 0.508)
			(layers "F.Cu" "F.Mask" "F.Paste")
			(net "BOOT_RDY_LED")
		)
	)
	(footprint ""
		(layer "F.Cu")
		(at 110.643924 -388.030974 90)
		(property "Reference" "R642"
			(at 0 0 90)
			(layer "F.SilkS")
			(hide yes)
			(effects
				(font
					(size 1.27 1.27)
				)
			)
		)
		(property "Value" ""
			(at 0 0 90)
			(layer "F.Fab")
			(effects
				(font
					(size 1.27 1.27)
				)
			)
		)
		(duplicate_pad_numbers_are_jumpers no)
		(fp_line
			(start 0.32512 -0.175006)
			(end 0.32512 0.175006)
			(stroke
				(width 0.1)
				(type default)
			)
			(layer "F.Fab")
		)
		(fp_line
			(start -0.32512 -0.175006)
			(end 0.32512 -0.175006)
			(stroke
				(width 0.1)
				(type default)
			)
			(layer "F.Fab")
		)
		(fp_line
			(start 0.32512 0.175006)
			(end -0.32512 0.175006)
			(stroke
				(width 0.1)
				(type default)
			)
			(layer "F.Fab")
		)
		(fp_line
			(start -0.32512 0.175006)
			(end -0.32512 -0.175006)
			(stroke
				(width 0.1)
				(type default)
			)
			(layer "F.Fab")
		)
		(pad "1" smd rect
			(at -0.2667 0 90)
			(size 0.3048 0.381)
			(layers "F.Cu" "F.Mask" "F.Paste")
			(net "CLK_100M_RETIMER_CPU1_P3_DP")
		)
		(pad "2" smd rect
			(at 0.2667 0 270)
			(size 0.3048 0.381)
			(layers "F.Cu" "F.Mask" "F.Paste")
			(net "GND")
		)
	)
	(footprint ""
		(layer "F.Cu")
		(at 11.557 -77.089)
		(property "Reference" "R8016"
			(at 0 0 0)
			(layer "F.SilkS")
			(hide yes)
			(effects
				(font
					(size 1.27 1.27)
				)
			)
		)
		(property "Value" ""
			(at 0 0 0)
			(layer "F.Fab")
			(effects
				(font
					(size 1.27 1.27)
				)
			)
		)
		(duplicate_pad_numbers_are_jumpers no)
		(fp_line
			(start -0.7874 -0.4064)
			(end 0.7874 -0.4064)
			(stroke
				(width 0.1524)
				(type default)
			)
			(layer "F.SilkS")
		)
		(fp_line
			(start -0.7874 0.4064)
			(end -0.7874 -0.4064)
			(stroke
				(width 0.1524)
				(type default)
			)
			(layer "F.SilkS")
		)
		(fp_line
			(start 0.7874 -0.4064)
			(end 0.7874 0.4064)
			(stroke
				(width 0.1524)
				(type default)
			)
			(layer "F.SilkS")
		)
		(fp_line
			(start 0.7874 0.4064)
			(end -0.7874 0.4064)
			(stroke
				(width 0.1524)
				(type default)
			)
			(layer "F.SilkS")
		)
		(fp_line
			(start -0.67945 -0.305054)
			(end -0.12065 -0.305054)
			(stroke
				(width 0.1)
				(type default)
			)
			(layer "F.Fab")
		)
		(fp_line
			(start -0.67945 0.3048)
			(end -0.67945 -0.305054)
			(stroke
				(width 0.1)
				(type default)
			)
			(layer "F.Fab")
		)
		(fp_line
			(start -0.12065 -0.305054)
			(end -0.12065 -0.2794)
			(stroke
				(width 0.1)
				(type default)
			)
			(layer "F.Fab")
		)
		(fp_line
			(start -0.12065 -0.2794)
			(end 0.12065 -0.2794)
			(stroke
				(width 0.1)
				(type default)
			)
			(layer "F.Fab")
		)
		(fp_line
			(start -0.12065 0.2794)
			(end -0.12065 0.3048)
			(stroke
				(width 0.1)
				(type default)
			)
			(layer "F.Fab")
		)
		(fp_line
			(start -0.12065 0.3048)
			(end -0.67945 0.3048)
			(stroke
				(width 0.1)
				(type default)
			)
			(layer "F.Fab")
		)
		(fp_line
			(start 0.120396 0.2794)
			(end -0.12065 0.2794)
			(stroke
				(width 0.1)
				(type default)
			)
			(layer "F.Fab")
		)
		(fp_line
			(start 0.120396 0.3048)
			(end 0.120396 0.2794)
			(stroke
				(width 0.1)
				(type default)
			)
			(layer "F.Fab")
		)
		(fp_line
			(start 0.12065 -0.3048)
			(end 0.67945 -0.3048)
			(stroke
				(width 0.1)
				(type default)
			)
			(layer "F.Fab")
		)
		(fp_line
			(start 0.12065 -0.2794)
			(end 0.12065 -0.3048)
			(stroke
				(width 0.1)
				(type default)
			)
			(layer "F.Fab")
		)
		(fp_line
			(start 0.67945 -0.3048)
			(end 0.67945 0.3048)
			(stroke
				(width 0.1)
				(type default)
			)
			(layer "F.Fab")
		)
		(fp_line
			(start 0.67945 0.3048)
			(end 0.120396 0.3048)
			(stroke
				(width 0.1)
				(type default)
			)
			(layer "F.Fab")
		)
		(pad "1" smd circle
			(at -0.40005 0)
			(size 0 0)
			(layers "F.Cu" "F.Mask" "F.Paste")
			(net "OCP_V3_2_PRSNT23_R_N")
		)
		(pad "2" smd circle
			(at 0.40005 0)
			(size 0 0)
			(layers "F.Cu" "F.Mask" "F.Paste")
			(net "OCP_V3_2_PRSNT23_R1_N")
		)
	)
	(footprint ""
		(layer "F.Cu")
		(at 204.851 -101.473)
		(property "Reference" "D8004"
			(at 3.037586 0.680466 0)
			(unlocked yes)
			(layer "F.SilkS")
			(effects
				(font
					(size 0.7874 0.5842)
					(thickness 0.1524)
				)
				(justify left)
			)
		)
		(property "Value" ""
			(at 0 0 0)
			(layer "F.Fab")
			(effects
				(font
					(size 1.27 1.27)
				)
			)
		)
		(duplicate_pad_numbers_are_jumpers no)
		(fp_line
			(start -2.050796 -0.700024)
			(end 2.050796 -0.700024)
			(stroke
				(width 0.1524)
				(type default)
			)
			(layer "F.SilkS")
		)
		(fp_line
			(start -2.050796 0.700024)
			(end -2.050796 -0.700024)
			(stroke
				(width 0.1524)
				(type default)
			)
			(layer "F.SilkS")
		)
		(fp_line
			(start -0.30607 -0.500126)
			(end -0.30607 0.500126)
			(stroke
				(width 0.1524)
				(type default)
			)
			(layer "F.SilkS")
		)
		(fp_line
			(start -0.30607 0.500126)
			(end 0.193802 0)
			(stroke
				(width 0.1524)
				(type default)
			)
			(layer "F.SilkS")
		)
		(fp_line
			(start 0.193802 0)
			(end -0.30607 -0.500126)
			(stroke
				(width 0.1524)
				(type default)
			)
			(layer "F.SilkS")
		)
		(fp_line
			(start 0.293878 -0.500126)
			(end 0.293878 0.500126)
			(stroke
				(width 0.1524)
				(type default)
			)
			(layer "F.SilkS")
		)
		(fp_line
			(start 2.050796 -0.700024)
			(end 2.050796 0.700024)
			(stroke
				(width 0.1524)
				(type default)
			)
			(layer "F.SilkS")
		)
		(fp_line
			(start 2.050796 0.700024)
			(end -2.050796 0.700024)
			(stroke
				(width 0.1524)
				(type default)
			)
			(layer "F.SilkS")
		)
		(fp_line
			(start 2.051304 0.635)
			(end 2.152904 0.635)
			(stroke
				(width 0.1524)
				(type default)
			)
			(layer "F.SilkS")
		)
		(fp_line
			(start 2.051304 0.6985)
			(end 2.051304 0.635)
			(stroke
				(width 0.1524)
				(type default)
			)
			(layer "F.SilkS")
		)
		(fp_line
			(start 2.064004 -0.6985)
			(end 2.229104 -0.6985)
			(stroke
				(width 0.1524)
				(type default)
			)
			(layer "F.SilkS")
		)
		(fp_line
			(start 2.064004 -0.6731)
			(end 2.064004 -0.6985)
			(stroke
				(width 0.1524)
				(type default)
			)
			(layer "F.SilkS")
		)
		(fp_line
			(start 2.152904 -0.6985)
			(end 2.343404 -0.6985)
			(stroke
				(width 0.1524)
				(type default)
			)
			(layer "F.SilkS")
		)
		(fp_line
			(start 2.152904 0.635)
			(end 2.152904 -0.6985)
			(stroke
				(width 0.1524)
				(type default)
			)
			(layer "F.SilkS")
		)
		(fp_line
			(start 2.229104 -0.6985)
			(end 2.229104 0.6985)
			(stroke
				(width 0.1524)
				(type default)
			)
			(layer "F.SilkS")
		)
		(fp_line
			(start 2.229104 0.6985)
			(end 2.051304 0.6985)
			(stroke
				(width 0.1524)
				(type default)
			)
			(layer "F.SilkS")
		)
		(fp_line
			(start 2.343404 -0.6985)
			(end 2.343404 0.6985)
			(stroke
				(width 0.1524)
				(type default)
			)
			(layer "F.SilkS")
		)
		(fp_line
			(start 2.343404 0.6985)
			(end 2.216404 0.6985)
			(stroke
				(width 0.1524)
				(type default)
			)
			(layer "F.SilkS")
		)
		(fp_line
			(start -0.899922 -0.700024)
			(end 0.899922 -0.700024)
			(stroke
				(width 0.1)
				(type default)
			)
			(layer "F.Fab")
		)
		(fp_line
			(start -0.899922 0.700024)
			(end -0.899922 -0.700024)
			(stroke
				(width 0.1)
				(type default)
			)
			(layer "F.Fab")
		)
		(fp_line
			(start 0.899922 -0.700024)
			(end 0.899922 0.700024)
			(stroke
				(width 0.1)
				(type default)
			)
			(layer "F.Fab")
		)
		(fp_line
			(start 0.899922 0.700024)
			(end -0.899922 0.700024)
			(stroke
				(width 0.1)
				(type default)
			)
			(layer "F.Fab")
		)
		(fp_text user "+"
			(at -2.772664 0.87757 90)
			(unlocked yes)
			(layer "F.SilkS")
			(effects
				(font
					(size 1.905 1.4224)
					(thickness 0.1524)
				)
				(justify left)
			)
		)
		(fp_text user "-"
			(at 3.880104 0.23495 180)
			(unlocked yes)
			(layer "F.SilkS")
			(effects
				(font
					(size 1.905 1.4224)
					(thickness 0.1524)
				)
				(justify left)
			)
		)
		(fp_text user "+"
			(at -3.123946 0.762 90)
			(unlocked yes)
			(layer "F.Fab")
			(effects
				(font
					(size 1.905 1.4224)
					(thickness 0.1524)
				)
				(justify left)
			)
		)
		(fp_text user "-"
			(at 3.880104 0.23495 180)
			(unlocked yes)
			(layer "F.Fab")
			(effects
				(font
					(size 1.905 1.4224)
					(thickness 0.1524)
				)
				(justify left)
			)
		)
		(pad "1" smd rect
			(at -1.199896 0 270)
			(size 0.6604 1.3716)
			(layers "F.Cu" "F.Mask" "F.Paste")
			(net "PWRGD_CHGL_CPU0_R1")
		)
		(pad "2" smd rect
			(at 1.199896 0 90)
			(size 0.6604 1.3716)
			(layers "F.Cu" "F.Mask" "F.Paste")
			(net "P3V3_AUX")
		)
	)
	(footprint ""
		(layer "F.Cu")
		(at 239.432592 -289.012122 180)
		(property "Reference" "C6757"
			(at 0 0 180)
			(layer "F.SilkS")
			(hide yes)
			(effects
				(font
					(size 1.27 1.27)
				)
			)
		)
		(property "Value" ""
			(at 0 0 180)
			(layer "F.Fab")
			(effects
				(font
					(size 1.27 1.27)
				)
			)
		)
		(duplicate_pad_numbers_are_jumpers no)
		(fp_line
			(start 0.7874 0.4064)
			(end -0.7874 0.4064)
			(stroke
				(width 0.1524)
				(type default)
			)
			(layer "F.SilkS")
		)
		(fp_line
			(start 0.7874 -0.4064)
			(end 0.7874 0.4064)
			(stroke
				(width 0.1524)
				(type default)
			)
			(layer "F.SilkS")
		)
		(fp_line
			(start -0.7874 0.4064)
			(end -0.7874 -0.4064)
			(stroke
				(width 0.1524)
				(type default)
			)
			(layer "F.SilkS")
		)
		(fp_line
			(start -0.7874 -0.4064)
			(end 0.7874 -0.4064)
			(stroke
				(width 0.1524)
				(type default)
			)
			(layer "F.SilkS")
		)
		(fp_line
			(start 0.67945 0.3048)
			(end 0.120396 0.3048)
			(stroke
				(width 0.1)
				(type default)
			)
			(layer "F.Fab")
		)
		(fp_line
			(start 0.67945 -0.3048)
			(end 0.67945 0.3048)
			(stroke
				(width 0.1)
				(type default)
			)
			(layer "F.Fab")
		)
		(fp_line
			(start 0.12065 -0.2794)
			(end 0.12065 -0.3048)
			(stroke
				(width 0.1)
				(type default)
			)
			(layer "F.Fab")
		)
		(fp_line
			(start 0.12065 -0.3048)
			(end 0.67945 -0.3048)
			(stroke
				(width 0.1)
				(type default)
			)
			(layer "F.Fab")
		)
		(fp_line
			(start 0.120396 0.3048)
			(end 0.120396 0.2794)
			(stroke
				(width 0.1)
				(type default)
			)
			(layer "F.Fab")
		)
		(fp_line
			(start 0.120396 0.2794)
			(end -0.12065 0.2794)
			(stroke
				(width 0.1)
				(type default)
			)
			(layer "F.Fab")
		)
		(fp_line
			(start -0.12065 0.3048)
			(end -0.67945 0.3048)
			(stroke
				(width 0.1)
				(type default)
			)
			(layer "F.Fab")
		)
		(fp_line
			(start -0.12065 0.2794)
			(end -0.12065 0.3048)
			(stroke
				(width 0.1)
				(type default)
			)
			(layer "F.Fab")
		)
		(fp_line
			(start -0.12065 -0.2794)
			(end 0.12065 -0.2794)
			(stroke
				(width 0.1)
				(type default)
			)
			(layer "F.Fab")
		)
		(fp_line
			(start -0.12065 -0.305054)
			(end -0.12065 -0.2794)
			(stroke
				(width 0.1)
				(type default)
			)
			(layer "F.Fab")
		)
		(fp_line
			(start -0.67945 0.3048)
			(end -0.67945 -0.305054)
			(stroke
				(width 0.1)
				(type default)
			)
			(layer "F.Fab")
		)
		(fp_line
			(start -0.67945 -0.305054)
			(end -0.12065 -0.305054)
			(stroke
				(width 0.1)
				(type default)
			)
			(layer "F.Fab")
		)
		(pad "1" smd circle
			(at -0.40005 0 180)
			(size 0 0)
			(layers "F.Cu" "F.Mask" "F.Paste")
			(net "P1V8_RETIMER_CPU0_EN")
		)
		(pad "2" smd circle
			(at 0.40005 0 180)
			(size 0 0)
			(layers "F.Cu" "F.Mask" "F.Paste")
			(net "GND")
		)
	)
)
